# S9S_MB_2U (Grand Teton) — schematic netlist excerpt (pin names and nets, part order shuffled) for the footprints in the layout excerpt that follows; sources: Cadence DE-HDL packaged netlist, KiCad conversion of 03242023_DA0F0TMBIJ0_F0T_Motherboard_J_brd_V01_OCP.brd

C67  Q_CAP  10UF 16V 10% X6S  pkg C0805  page 103 : A = P12V_S3_AUX_CPU1_NVDIMM ; B = GND
R4022  Q_RES  33.2 1% CHIP  pkg 0402LF  page 226 : A = H_CPU_RMCA_LVC2_R1_N ; B = H_CPU_RMCA_LVC2_R2_N
PC590  Q_CAPP  330UF 2.5V +10/-35% EMPTY  pkg SMLF  page 285 : A = PVCCIN_CPU1 ; B = GND

(kicad_pcb
	(version 20260206)
	(generator "pcbnew")
	(generator_version "10.0")
	(general
		(thickness 1.6)
		(legacy_teardrops no)
	)
	(paper "A4")
	(title_block
		(title "03242023_DA0F0TMBIJ0_F0T_Motherboard_J_brd_V01_OCP.brd")
		(comment 1 "Grand Teton / footprints 4238-4240 of 6105")
	)
	(layers
		(0 "F.Cu" signal "TOP")
		(4 "In1.Cu" signal "GND")
		(6 "In2.Cu" signal "IN1")
		(8 "In3.Cu" signal "GND1")
		(10 "In4.Cu" signal "IN2")
		(12 "In5.Cu" signal "GND2")
		(14 "In6.Cu" signal "IN3")
		(16 "In7.Cu" signal "GND3")
		(18 "In8.Cu" signal "VCC")
		(20 "In9.Cu" signal "VCC1")
		(22 "In10.Cu" signal "GND4")
		(24 "In11.Cu" signal "IN4")
		(26 "In12.Cu" signal "GND5")
		(28 "In13.Cu" signal "IN5")
		(30 "In14.Cu" signal "GND6")
		(32 "In15.Cu" signal "IN6")
		(34 "In16.Cu" signal "GND7")
		(2 "B.Cu" signal "BOTTOM")
		(9 "F.Adhes" user "F.Adhesive")
		(11 "B.Adhes" user "B.Adhesive")
		(13 "F.Paste" user "Package Geometry/Pastemask Top")
		(15 "B.Paste" user "Package Geometry/Pastemask Bottom")
		(5 "F.SilkS" user "Ref Des/Silkscreen Top")
		(7 "B.SilkS" user "Ref Des/Silkscreen Bottom")
		(1 "F.Mask" user "Board Geometry/Soldermask Top")
		(3 "B.Mask" user "Board Geometry/Soldermask Bottom")
		(17 "Dwgs.User" user "User.Drawings")
		(19 "Cmts.User" user "User.Comments")
		(21 "Eco1.User" user "User.Eco1")
		(23 "Eco2.User" user "User.Eco2")
		(25 "Edge.Cuts" user "Board Geometry/Outline")
		(27 "Margin" user)
		(31 "F.CrtYd" user "Package Geometry/Place Bound Top")
		(29 "B.CrtYd" user "Package Geometry/Place Bound Bottom")
		(35 "F.Fab" user "Ref Des/Assembly Top")
		(33 "B.Fab" user "Ref Des/Assembly Bottom")
	)
	(footprint ""
		(layer "B.Cu")
		(at 104.49052 -326.994012 -90)
		(property "Reference" "PC590"
			(at 0 0 90)
			(layer "B.SilkS")
			(hide yes)
			(effects
				(font
					(size 1.27 1.27)
				)
				(justify mirror)
			)
		)
		(property "Value" ""
			(at 0 0 90)
			(layer "B.Fab")
			(effects
				(font
					(size 1.27 1.27)
				)
				(justify mirror)
			)
		)
		(duplicate_pad_numbers_are_jumpers no)
		(fp_line
			(start -4.533392 2.249932)
			(end 4.533392 2.249932)
			(stroke
				(width 0.1524)
				(type default)
			)
			(layer "B.SilkS")
		)
		(fp_line
			(start 4.533392 2.249932)
			(end 4.533392 -2.249932)
			(stroke
				(width 0.1524)
				(type default)
			)
			(layer "B.SilkS")
		)
		(fp_line
			(start -4.533392 -2.249932)
			(end -4.533392 2.249932)
			(stroke
				(width 0.1524)
				(type default)
			)
			(layer "B.SilkS")
		)
		(fp_line
			(start 4.533392 -2.249932)
			(end -4.533392 -2.249932)
			(stroke
				(width 0.1524)
				(type default)
			)
			(layer "B.SilkS")
		)
		(fp_rect
			(start 5.39242 2.326132)
			(end 4.533392 -2.326132)
			(stroke
				(width 0)
				(type default)
			)
			(fill yes)
			(layer "B.SilkS")
		)
		(fp_line
			(start -3.750056 2.249932)
			(end 3.750056 2.249932)
			(stroke
				(width 0.1)
				(type default)
			)
			(layer "B.Fab")
		)
		(fp_line
			(start 3.750056 2.249932)
			(end 3.750056 -2.249932)
			(stroke
				(width 0.1)
				(type default)
			)
			(layer "B.Fab")
		)
		(fp_line
			(start -3.750056 -2.249932)
			(end -3.750056 2.249932)
			(stroke
				(width 0.1)
				(type default)
			)
			(layer "B.Fab")
		)
		(fp_line
			(start 3.750056 -2.249932)
			(end -3.750056 -2.249932)
			(stroke
				(width 0.1)
				(type default)
			)
			(layer "B.Fab")
		)
		(fp_text user "+"
			(at 6.322314 0.786384 180)
			(unlocked yes)
			(layer "B.SilkS")
			(effects
				(font
					(size 1.905 1.4224)
					(thickness 0.1524)
				)
				(justify left mirror)
			)
		)
		(fp_text user "-"
			(at -4.575556 0.51435 270)
			(unlocked yes)
			(layer "B.SilkS")
			(effects
				(font
					(size 1.905 1.4224)
					(thickness 0.1524)
				)
				(justify left mirror)
			)
		)
		(fp_text user "+"
			(at 6.322314 0.786384 180)
			(unlocked yes)
			(layer "B.Fab")
			(effects
				(font
					(size 1.905 1.4224)
					(thickness 0.1524)
				)
				(justify left mirror)
			)
		)
		(fp_text user "-"
			(at -4.8514 -0.14605 270)
			(unlocked yes)
			(layer "B.Fab")
			(effects
				(font
					(size 1.905 1.4224)
					(thickness 0.1524)
				)
				(justify left mirror)
			)
		)
		(pad "1" smd rect
			(at 3.199892 0 90)
			(size 2.413 2.8194)
			(layers "B.Cu" "B.Mask" "B.Paste")
			(net "PVCCIN_CPU1")
		)
		(pad "2" smd rect
			(at -3.199892 0 90)
			(size 2.413 2.8194)
			(layers "B.Cu" "B.Mask" "B.Paste")
			(net "GND")
		)
	)
	(footprint ""
		(layer "B.Cu")
		(at 30.784546 -321.554856 -90)
		(property "Reference" "C67"
			(at 0 0 90)
			(layer "B.SilkS")
			(hide yes)
			(effects
				(font
					(size 1.27 1.27)
				)
				(justify mirror)
			)
		)
		(property "Value" ""
			(at 0 0 90)
			(layer "B.Fab")
			(effects
				(font
					(size 1.27 1.27)
				)
				(justify mirror)
			)
		)
		(duplicate_pad_numbers_are_jumpers no)
		(fp_line
			(start -1.524 0.762)
			(end 1.524 0.762)
			(stroke
				(width 0.1524)
				(type default)
			)
			(layer "B.SilkS")
		)
		(fp_line
			(start 1.524 0.762)
			(end 1.524 -0.762)
			(stroke
				(width 0.1524)
				(type default)
			)
			(layer "B.SilkS")
		)
		(fp_line
			(start -1.524 -0.762)
			(end -1.524 0.762)
			(stroke
				(width 0.1524)
				(type default)
			)
			(layer "B.SilkS")
		)
		(fp_line
			(start 1.524 -0.762)
			(end -1.524 -0.762)
			(stroke
				(width 0.1524)
				(type default)
			)
			(layer "B.SilkS")
		)
		(fp_line
			(start -1.1049 0.724916)
			(end -1.1049 -0.724916)
			(stroke
				(width 0.1)
				(type default)
			)
			(layer "B.Fab")
		)
		(fp_line
			(start 1.1049 0.724916)
			(end -1.1049 0.724916)
			(stroke
				(width 0.1)
				(type default)
			)
			(layer "B.Fab")
		)
		(fp_line
			(start -1.1049 -0.724916)
			(end 1.1049 -0.724916)
			(stroke
				(width 0.1)
				(type default)
			)
			(layer "B.Fab")
		)
		(fp_line
			(start 1.1049 -0.724916)
			(end 1.1049 0.724916)
			(stroke
				(width 0.1)
				(type default)
			)
			(layer "B.Fab")
		)
		(pad "1" smd rect
			(at 0.889 0 270)
			(size 1.016 1.27)
			(layers "B.Cu" "B.Mask" "B.Paste")
			(net "P12V_S3_AUX_CPU1_NVDIMM")
		)
		(pad "2" smd rect
			(at -0.889 0 270)
			(size 1.016 1.27)
			(layers "B.Cu" "B.Mask" "B.Paste")
			(net "GND")
		)
	)
	(footprint ""
		(layer "B.Cu")
		(at 114.427 -86.705948 180)
		(property "Reference" "R4022"
			(at 0 0 0)
			(layer "B.SilkS")
			(hide yes)
			(effects
				(font
					(size 1.27 1.27)
				)
				(justify mirror)
			)
		)
		(property "Value" ""
			(at 0 0 0)
			(layer "B.Fab")
			(effects
				(font
					(size 1.27 1.27)
				)
				(justify mirror)
			)
		)
		(duplicate_pad_numbers_are_jumpers no)
		(fp_line
			(start 0.7874 0.4064)
			(end 0.7874 -0.4064)
			(stroke
				(width 0.1524)
				(type default)
			)
			(layer "B.SilkS")
		)
		(fp_line
			(start 0.7874 -0.4064)
			(end -0.7874 -0.4064)
			(stroke
				(width 0.1524)
				(type default)
			)
			(layer "B.SilkS")
		)
		(fp_line
			(start -0.7874 0.4064)
			(end 0.7874 0.4064)
			(stroke
				(width 0.1524)
				(type default)
			)
			(layer "B.SilkS")
		)
		(fp_line
			(start -0.7874 -0.4064)
			(end -0.7874 0.4064)
			(stroke
				(width 0.1524)
				(type default)
			)
			(layer "B.SilkS")
		)
		(fp_line
			(start 0.67945 0.3048)
			(end 0.67945 -0.305054)
			(stroke
				(width 0.1)
				(type default)
			)
			(layer "B.Fab")
		)
		(fp_line
			(start 0.67945 -0.305054)
			(end 0.12065 -0.305054)
			(stroke
				(width 0.1)
				(type default)
			)
			(layer "B.Fab")
		)
		(fp_line
			(start 0.12065 0.3048)
			(end 0.67945 0.3048)
			(stroke
				(width 0.1)
				(type default)
			)
			(layer "B.Fab")
		)
		(fp_line
			(start 0.12065 0.2794)
			(end 0.12065 0.3048)
			(stroke
				(width 0.1)
				(type default)
			)
			(layer "B.Fab")
		)
		(fp_line
			(start 0.12065 -0.2794)
			(end -0.12065 -0.2794)
			(stroke
				(width 0.1)
				(type default)
			)
			(layer "B.Fab")
		)
		(fp_line
			(start 0.12065 -0.305054)
			(end 0.12065 -0.2794)
			(stroke
				(width 0.1)
				(type default)
			)
			(layer "B.Fab")
		)
		(fp_line
			(start -0.120396 0.3048)
			(end -0.120396 0.2794)
			(stroke
				(width 0.1)
				(type default)
			)
			(layer "B.Fab")
		)
		(fp_line
			(start -0.120396 0.2794)
			(end 0.12065 0.2794)
			(stroke
				(width 0.1)
				(type default)
			)
			(layer "B.Fab")
		)
		(fp_line
			(start -0.12065 -0.2794)
			(end -0.12065 -0.3048)
			(stroke
				(width 0.1)
				(type default)
			)
			(layer "B.Fab")
		)
		(fp_line
			(start -0.12065 -0.3048)
			(end -0.67945 -0.3048)
			(stroke
				(width 0.1)
				(type default)
			)
			(layer "B.Fab")
		)
		(fp_line
			(start -0.67945 0.3048)
			(end -0.120396 0.3048)
			(stroke
				(width 0.1)
				(type default)
			)
			(layer "B.Fab")
		)
		(fp_line
			(start -0.67945 -0.3048)
			(end -0.67945 0.3048)
			(stroke
				(width 0.1)
				(type default)
			)
			(layer "B.Fab")
		)
		(pad "1" smd circle
			(at 0.40005 0)
			(size 0 0)
			(layers "B.Cu" "B.Mask" "B.Paste")
			(net "H_CPU_RMCA_LVC2_R1_N")
		)
		(pad "2" smd circle
			(at -0.40005 0)
			(size 0 0)
			(layers "B.Cu" "B.Mask" "B.Paste")
			(net "H_CPU_RMCA_LVC2_R2_N")
		)
	)
)
